FILE_TYPE=LIBRARY_PARTS;
primitive 'CONN6_C74770005';
  pin
    'IO1':
      PIN_NUMBER='(1)';
      PIN_TYPE='UNSPEC';
      NO_LOAD_CHECK='BOTH';
      NO_IO_CHECK='BOTH';
      ALLOW_CONNECT='TRUE';
    'IO2':
      PIN_NUMBER='(2)';
      PIN_TYPE='UNSPEC';
      NO_LOAD_CHECK='BOTH';
      NO_IO_CHECK='BOTH';
      ALLOW_CONNECT='TRUE';
    'IO3':
      PIN_NUMBER='(3)';
      PIN_TYPE='UNSPEC';
      NO_LOAD_CHECK='BOTH';
      NO_IO_CHECK='BOTH';
      ALLOW_CONNECT='TRUE';
    'IO4':
      PIN_NUMBER='(4)';
      PIN_TYPE='UNSPEC';
      NO_LOAD_CHECK='BOTH';
      NO_IO_CHECK='BOTH';
      ALLOW_CONNECT='TRUE';
    'IO5':
      PIN_NUMBER='(5)';
      PIN_TYPE='UNSPEC';
      NO_LOAD_CHECK='BOTH';
      NO_IO_CHECK='BOTH';
      ALLOW_CONNECT='TRUE';
    'IO6':
      PIN_NUMBER='(6)';
      PIN_TYPE='UNSPEC';
      NO_LOAD_CHECK='BOTH';
      NO_IO_CHECK='BOTH';
      ALLOW_CONNECT='TRUE';
  end_pin;
  body
    PART_NAME='CONN6_C74770005';
    PHYS_DES_PREFIX='J';
  end_body;
end_primitive;
END.
